(kicad_pcb
	(version 20260206)
	(generator "pcbnew")
	(generator_version "10.0")
	(general
		(thickness 1.6)
		(legacy_teardrops no)
	)
	(paper "A4")
	(title_block
		(title "Bryce Canyon_SCC_16316-1_OCP.brd")
		(comment 1 "Bryce Canyon / footprint 64 of 1561 (U1), pads 465-582 of 1020")
	)
	(layers
		(0 "F.Cu" signal "TOP")
		(4 "In1.Cu" signal "L2GND")
		(6 "In2.Cu" signal "L3")
		(8 "In3.Cu" signal "L4VCC")
		(10 "In4.Cu" signal "L5VCC")
		(12 "In5.Cu" signal "L6")
		(14 "In6.Cu" signal "L7GND")
		(2 "B.Cu" signal "BOTTOM")
		(9 "F.Adhes" user "F.Adhesive")
		(11 "B.Adhes" user "B.Adhesive")
		(13 "F.Paste" user "Package Geometry/Pastemask Top")
		(15 "B.Paste" user "Package Geometry/Pastemask Bottom")
		(5 "F.SilkS" user "Ref Des/Silkscreen Top")
		(7 "B.SilkS" user "Ref Des/Silkscreen Bottom")
		(1 "F.Mask" user "Board Geometry/Soldermask Top")
		(3 "B.Mask" user "Board Geometry/Soldermask Bottom")
		(17 "Dwgs.User" user "User.Drawings")
		(19 "Cmts.User" user "User.Comments")
		(21 "Eco1.User" user "User.Eco1")
		(23 "Eco2.User" user "User.Eco2")
		(25 "Edge.Cuts" user "Board Geometry/Outline")
		(27 "Margin" user)
		(31 "F.CrtYd" user "Package Geometry/Place Bound Top")
		(29 "B.CrtYd" user "Package Geometry/Place Bound Bottom")
		(35 "F.Fab" user "Ref Des/Assembly Top")
		(33 "B.Fab" user "Ref Des/Assembly Bottom")
	)
	(footprint ""
		(layer "F.Cu")
		(at 115.000024 -67.00012)
		(property "Reference" "U1"
			(at 0 0 0)
			(layer "F.SilkS")
			(hide yes)
			(effects
				(font
					(size 1.27 1.27)
				)
			)
		)
		(property "Value" "LSISAS3X48-GP"
			(at -24.358092 -5.0292 0)
			(unlocked yes)
			(layer "F.Fab")
			(hide yes)
			(effects
				(font
					(size 1.016 1.016)
					(thickness 0.1524)
				)
			)
		)
		(property "Device Type" "BGA1020C33H83"
			(at -24.358092 -6.5532 0)
			(unlocked yes)
			(layer "F.Fab")
			(hide yes)
			(effects
				(font
					(size 1.016 1.016)
					(thickness 0.1524)
				)
			)
		)
		(duplicate_pad_numbers_are_jumpers no)
		(pad "C21" smd circle
			(at 4.500118 -13.5001)
			(size 0.4572 0.4572)
			(layers "F.Cu" "F.Mask" "F.Paste")
			(net "SCC_TYPE_3_LS")
		)
		(pad "C22" smd circle
			(at 5.500116 -13.5001)
			(size 0.4572 0.4572)
			(layers "F.Cu" "F.Mask" "F.Paste")
			(net "GND")
		)
		(pad "C23" smd circle
			(at 6.500114 -13.5001)
			(size 0.4572 0.4572)
			(layers "F.Cu" "F.Mask" "F.Paste")
			(net "Net_1209")
		)
		(pad "C24" smd circle
			(at 7.500112 -13.5001)
			(size 0.4572 0.4572)
			(layers "F.Cu" "F.Mask" "F.Paste")
			(net "GND")
		)
		(pad "C25" smd circle
			(at 8.50011 -13.5001)
			(size 0.4572 0.4572)
			(layers "F.Cu" "F.Mask" "F.Paste")
			(net "EXP_RGMII_RXC")
		)
		(pad "C26" smd circle
			(at 9.500108 -13.5001)
			(size 0.4572 0.4572)
			(layers "F.Cu" "F.Mask" "F.Paste")
			(net "GND")
		)
		(pad "C27" smd circle
			(at 10.500106 -13.5001)
			(size 0.4572 0.4572)
			(layers "F.Cu" "F.Mask" "F.Paste")
			(net "ICE_TDO")
		)
		(pad "C28" smd circle
			(at 11.500104 -13.5001)
			(size 0.4572 0.4572)
			(layers "F.Cu" "F.Mask" "F.Paste")
			(net "GND")
		)
		(pad "C29" smd circle
			(at 12.500102 -13.5001)
			(size 0.4572 0.4572)
			(layers "F.Cu" "F.Mask" "F.Paste")
			(net "EXP_I2C_SDA11")
		)
		(pad "C30" smd circle
			(at 13.5001 -13.5001)
			(size 0.508 0.508)
			(layers "F.Cu" "F.Mask" "F.Paste")
			(net "GND")
		)
		(pad "C31" smd circle
			(at 14.500098 -13.5001)
			(size 0.508 0.508)
			(layers "F.Cu" "F.Mask" "F.Paste")
			(net "I2C_DRIVE_FLT_LED_SCL6_LS")
		)
		(pad "C32" smd circle
			(at 15.500096 -13.5001)
			(size 0.508 0.508)
			(layers "F.Cu" "F.Mask" "F.Paste")
			(net "GND")
		)
		(pad "D1" smd circle
			(at -15.500096 -12.500102)
			(size 0.4572 0.4572)
			(layers "F.Cu" "F.Mask" "F.Paste")
			(net "Net_1251")
		)
		(pad "D2" smd circle
			(at -14.500098 -12.500102)
			(size 0.4572 0.4572)
			(layers "F.Cu" "F.Mask" "F.Paste")
			(net "VDDIO_DDR")
		)
		(pad "D3" smd circle
			(at -13.5001 -12.500102)
			(size 0.4572 0.4572)
			(layers "F.Cu" "F.Mask" "F.Paste")
			(net "Net_1250")
		)
		(pad "D4" smd circle
			(at -12.500102 -12.500102)
			(size 0.4572 0.4572)
			(layers "F.Cu" "F.Mask" "F.Paste")
			(net "VDDIO_DDR")
		)
		(pad "D5" smd circle
			(at -11.500104 -12.500102)
			(size 0.4572 0.4572)
			(layers "F.Cu" "F.Mask" "F.Paste")
			(net "Net_1249")
		)
		(pad "D6" smd circle
			(at -10.500106 -12.500102)
			(size 0.4572 0.4572)
			(layers "F.Cu" "F.Mask" "F.Paste")
			(net "GND")
		)
		(pad "D7" smd circle
			(at -9.500108 -12.500102)
			(size 0.4572 0.4572)
			(layers "F.Cu" "F.Mask" "F.Paste")
			(net "EXP_ADC_IN0")
		)
		(pad "D8" smd circle
			(at -8.50011 -12.500102)
			(size 0.4572 0.4572)
			(layers "F.Cu" "F.Mask" "F.Paste")
			(net "P1V8_E")
		)
		(pad "D9" smd circle
			(at -7.500112 -12.500102)
			(size 0.4572 0.4572)
			(layers "F.Cu" "F.Mask" "F.Paste")
			(net "DRIVE_4_ACT")
		)
		(pad "D10" smd circle
			(at -6.500114 -12.500102)
			(size 0.4572 0.4572)
			(layers "F.Cu" "F.Mask" "F.Paste")
			(net "LSI_TRST_N")
		)
		(pad "D11" smd circle
			(at -5.500116 -12.500102)
			(size 0.4572 0.4572)
			(layers "F.Cu" "F.Mask" "F.Paste")
			(net "EXP_CPU_MODE_1")
		)
		(pad "D12" smd circle
			(at -4.500118 -12.500102)
			(size 0.4572 0.4572)
			(layers "F.Cu" "F.Mask" "F.Paste")
			(net "EXP_XM_WE_N")
		)
		(pad "D13" smd circle
			(at -3.50012 -12.500102)
			(size 0.4572 0.4572)
			(layers "F.Cu" "F.Mask" "F.Paste")
			(net "XM_DATA8")
		)
		(pad "D14" smd circle
			(at -2.500122 -12.500102)
			(size 0.4572 0.4572)
			(layers "F.Cu" "F.Mask" "F.Paste")
			(net "P1V8_E")
		)
		(pad "D15" smd circle
			(at -1.500124 -12.500102)
			(size 0.4572 0.4572)
			(layers "F.Cu" "F.Mask" "F.Paste")
			(net "EXP_XM_ADDR_9")
		)
		(pad "D16" smd circle
			(at -0.500126 -12.500102)
			(size 0.4572 0.4572)
			(layers "F.Cu" "F.Mask" "F.Paste")
			(net "P1V8_E")
		)
		(pad "D17" smd circle
			(at 0.500126 -12.500102)
			(size 0.4572 0.4572)
			(layers "F.Cu" "F.Mask" "F.Paste")
			(net "EXP_XM_ADDR_17")
		)
		(pad "D18" smd circle
			(at 1.500124 -12.500102)
			(size 0.4572 0.4572)
			(layers "F.Cu" "F.Mask" "F.Paste")
			(net "P1V8_E")
		)
		(pad "D19" smd circle
			(at 2.500122 -12.500102)
			(size 0.4572 0.4572)
			(layers "F.Cu" "F.Mask" "F.Paste")
			(net "PWM_OUT_ZONE_C_LS")
		)
		(pad "D20" smd circle
			(at 3.50012 -12.500102)
			(size 0.4572 0.4572)
			(layers "F.Cu" "F.Mask" "F.Paste")
			(net "P1V8_E")
		)
		(pad "D21" smd circle
			(at 4.500118 -12.500102)
			(size 0.4572 0.4572)
			(layers "F.Cu" "F.Mask" "F.Paste")
			(net "SLOT_ID_1")
		)
		(pad "D22" smd circle
			(at 5.500116 -12.500102)
			(size 0.4572 0.4572)
			(layers "F.Cu" "F.Mask" "F.Paste")
			(net "P1V8_E")
		)
		(pad "D23" smd circle
			(at 6.500114 -12.500102)
			(size 0.4572 0.4572)
			(layers "F.Cu" "F.Mask" "F.Paste")
			(net "Net_1208")
		)
		(pad "D24" smd circle
			(at 7.500112 -12.500102)
			(size 0.4572 0.4572)
			(layers "F.Cu" "F.Mask" "F.Paste")
			(net "P1V8_E")
		)
		(pad "D25" smd circle
			(at 8.50011 -12.500102)
			(size 0.4572 0.4572)
			(layers "F.Cu" "F.Mask" "F.Paste")
			(net "Net_1207")
		)
		(pad "D26" smd circle
			(at 9.500108 -12.500102)
			(size 0.4572 0.4572)
			(layers "F.Cu" "F.Mask" "F.Paste")
			(net "P1V8_E")
		)
		(pad "D27" smd circle
			(at 10.500106 -12.500102)
			(size 0.4572 0.4572)
			(layers "F.Cu" "F.Mask" "F.Paste")
			(net "UART_RTS")
		)
		(pad "D28" smd circle
			(at 11.500104 -12.500102)
			(size 0.4572 0.4572)
			(layers "F.Cu" "F.Mask" "F.Paste")
			(net "P1V8_E")
		)
		(pad "D29" smd circle
			(at 12.500102 -12.500102)
			(size 0.4572 0.4572)
			(layers "F.Cu" "F.Mask" "F.Paste")
			(net "EXP_I2C_SCL11")
		)
		(pad "D30" smd circle
			(at 13.5001 -12.500102)
			(size 0.4572 0.4572)
			(layers "F.Cu" "F.Mask" "F.Paste")
			(net "P1V8_E")
		)
		(pad "D31" smd circle
			(at 14.500098 -12.500102)
			(size 0.4572 0.4572)
			(layers "F.Cu" "F.Mask" "F.Paste")
			(net "I2C_DRIVE_INS_SCL5_LS")
		)
		(pad "D32" smd circle
			(at 15.500096 -12.500102)
			(size 0.4572 0.4572)
			(layers "F.Cu" "F.Mask" "F.Paste")
			(net "P1V8_E")
		)
		(pad "E1" smd circle
			(at -15.500096 -11.500104)
			(size 0.4572 0.4572)
			(layers "F.Cu" "F.Mask" "F.Paste")
			(net "Net_1248")
		)
		(pad "E2" smd circle
			(at -14.500098 -11.500104)
			(size 0.4572 0.4572)
			(layers "F.Cu" "F.Mask" "F.Paste")
			(net "Net_1247")
		)
		(pad "E3" smd circle
			(at -13.5001 -11.500104)
			(size 0.4572 0.4572)
			(layers "F.Cu" "F.Mask" "F.Paste")
			(net "GND")
		)
		(pad "E4" smd circle
			(at -12.500102 -11.500104)
			(size 0.4572 0.4572)
			(layers "F.Cu" "F.Mask" "F.Paste")
			(net "Net_1246")
		)
		(pad "E5" smd circle
			(at -11.500104 -11.500104)
			(size 0.4572 0.4572)
			(layers "F.Cu" "F.Mask" "F.Paste")
			(net "Net_1245")
		)
		(pad "E6" smd circle
			(at -10.500106 -11.500104)
			(size 0.4572 0.4572)
			(layers "F.Cu" "F.Mask" "F.Paste")
			(net "GND")
		)
		(pad "E7" smd circle
			(at -9.500108 -11.500104)
			(size 0.4572 0.4572)
			(layers "F.Cu" "F.Mask" "F.Paste")
			(net "GND")
		)
		(pad "E8" smd circle
			(at -8.50011 -11.500104)
			(size 0.4572 0.4572)
			(layers "F.Cu" "F.Mask" "F.Paste")
			(net "TESTIBIAS")
		)
		(pad "E9" smd circle
			(at -7.500112 -11.500104)
			(size 0.4572 0.4572)
			(layers "F.Cu" "F.Mask" "F.Paste")
			(net "DRIVE_7_ACT")
		)
		(pad "E10" smd circle
			(at -6.500114 -11.500104)
			(size 0.4572 0.4572)
			(layers "F.Cu" "F.Mask" "F.Paste")
			(net "GND")
		)
		(pad "E11" smd circle
			(at -5.500116 -11.500104)
			(size 0.4572 0.4572)
			(layers "F.Cu" "F.Mask" "F.Paste")
			(net "EXP_IDDT")
		)
		(pad "E12" smd circle
			(at -4.500118 -11.500104)
			(size 0.4572 0.4572)
			(layers "F.Cu" "F.Mask" "F.Paste")
			(net "GND")
		)
		(pad "E13" smd circle
			(at -3.50012 -11.500104)
			(size 0.4572 0.4572)
			(layers "F.Cu" "F.Mask" "F.Paste")
			(net "XM_GP_CS_1#_TP")
		)
		(pad "E14" smd circle
			(at -2.500122 -11.500104)
			(size 0.4572 0.4572)
			(layers "F.Cu" "F.Mask" "F.Paste")
			(net "XM_DATA14")
		)
		(pad "E15" smd circle
			(at -1.500124 -11.500104)
			(size 0.4572 0.4572)
			(layers "F.Cu" "F.Mask" "F.Paste")
			(net "EXP_XM_ADDR_7")
		)
		(pad "E16" smd circle
			(at -0.500126 -11.500104)
			(size 0.4572 0.4572)
			(layers "F.Cu" "F.Mask" "F.Paste")
			(net "EXP_XM_ADDR_22")
		)
		(pad "E17" smd circle
			(at 0.500126 -11.500104)
			(size 0.4572 0.4572)
			(layers "F.Cu" "F.Mask" "F.Paste")
			(net "EXP_XM_ADDR_14")
		)
		(pad "E18" smd circle
			(at 1.500124 -11.500104)
			(size 0.4572 0.4572)
			(layers "F.Cu" "F.Mask" "F.Paste")
			(net "EXP_XM_ADDR_12")
		)
		(pad "E19" smd circle
			(at 2.500122 -11.500104)
			(size 0.4572 0.4572)
			(layers "F.Cu" "F.Mask" "F.Paste")
			(net "SCC_RMT_HEARTBEAT_LS")
		)
		(pad "E20" smd circle
			(at 3.50012 -11.500104)
			(size 0.4572 0.4572)
			(layers "F.Cu" "F.Mask" "F.Paste")
			(net "EXP_GPIO12")
		)
		(pad "E21" smd circle
			(at 4.500118 -11.500104)
			(size 0.4572 0.4572)
			(layers "F.Cu" "F.Mask" "F.Paste")
			(net "SLOT_ID_0")
		)
		(pad "E22" smd circle
			(at 5.500116 -11.500104)
			(size 0.4572 0.4572)
			(layers "F.Cu" "F.Mask" "F.Paste")
			(net "USB_DIR")
		)
		(pad "E23" smd circle
			(at 6.500114 -11.500104)
			(size 0.4572 0.4572)
			(layers "F.Cu" "F.Mask" "F.Paste")
			(net "Net_1206")
		)
		(pad "E24" smd circle
			(at 7.500112 -11.500104)
			(size 0.4572 0.4572)
			(layers "F.Cu" "F.Mask" "F.Paste")
			(net "Net_1205")
		)
		(pad "E25" smd circle
			(at 8.50011 -11.500104)
			(size 0.4572 0.4572)
			(layers "F.Cu" "F.Mask" "F.Paste")
			(net "ICE_TMS")
		)
		(pad "E26" smd circle
			(at 9.500108 -11.500104)
			(size 0.4572 0.4572)
			(layers "F.Cu" "F.Mask" "F.Paste")
			(net "EXP_SIO_LOAD_IN")
		)
		(pad "E27" smd circle
			(at 10.500106 -11.500104)
			(size 0.4572 0.4572)
			(layers "F.Cu" "F.Mask" "F.Paste")
			(net "I2C_EXP_IOC_SDA8")
		)
		(pad "E28" smd circle
			(at 11.500104 -11.500104)
			(size 0.4572 0.4572)
			(layers "F.Cu" "F.Mask" "F.Paste")
			(net "I2C_DRIVE_INS_SDA5_LS")
		)
		(pad "E29" smd circle
			(at 12.500102 -11.500104)
			(size 0.4572 0.4572)
			(layers "F.Cu" "F.Mask" "F.Paste")
			(net "I2C_DRIVE_PWR_SCL4_LS")
		)
		(pad "E30" smd circle
			(at 13.5001 -11.500104)
			(size 0.4572 0.4572)
			(layers "F.Cu" "F.Mask" "F.Paste")
			(net "I2C_BMC_RMT_SDA1_LS")
		)
		(pad "E31" smd circle
			(at 14.500098 -11.500104)
			(size 0.4572 0.4572)
			(layers "F.Cu" "F.Mask" "F.Paste")
			(net "I2C_BMC_RMT_SCL1_LS")
		)
		(pad "E32" smd circle
			(at 15.500096 -11.500104)
			(size 0.4572 0.4572)
			(layers "F.Cu" "F.Mask" "F.Paste")
			(net "I2C_BMC_LOC_SCL0_LS")
		)
		(pad "F1" smd circle
			(at -15.500096 -10.500106)
			(size 0.4572 0.4572)
			(layers "F.Cu" "F.Mask" "F.Paste")
			(net "Net_1244")
		)
		(pad "F2" smd circle
			(at -14.500098 -10.500106)
			(size 0.4572 0.4572)
			(layers "F.Cu" "F.Mask" "F.Paste")
			(net "VDDIO_DDR")
		)
		(pad "F3" smd circle
			(at -13.5001 -10.500106)
			(size 0.4572 0.4572)
			(layers "F.Cu" "F.Mask" "F.Paste")
			(net "Net_1243")
		)
		(pad "F4" smd circle
			(at -12.500102 -10.500106)
			(size 0.4572 0.4572)
			(layers "F.Cu" "F.Mask" "F.Paste")
			(net "VDDIO_DDR")
		)
		(pad "F5" smd circle
			(at -11.500104 -10.500106)
			(size 0.4572 0.4572)
			(layers "F.Cu" "F.Mask" "F.Paste")
			(net "Net_1242")
		)
		(pad "F6" smd circle
			(at -10.500106 -10.500106)
			(size 0.4572 0.4572)
			(layers "F.Cu" "F.Mask" "F.Paste")
			(net "VDDIO_DDR")
		)
		(pad "F7" smd circle
			(at -9.500108 -10.500106)
			(size 0.4572 0.4572)
			(layers "F.Cu" "F.Mask" "F.Paste")
			(net "GND")
		)
		(pad "F8" smd circle
			(at -8.50011 -10.500106)
			(size 0.4572 0.4572)
			(layers "F.Cu" "F.Mask" "F.Paste")
			(net "GND")
		)
		(pad "F9" smd circle
			(at -7.500112 -10.500106)
			(size 0.4572 0.4572)
			(layers "F.Cu" "F.Mask" "F.Paste")
			(net "SYS_PWR_LED_LS_N")
		)
		(pad "F10" smd circle
			(at -6.500114 -10.500106)
			(size 0.4572 0.4572)
			(layers "F.Cu" "F.Mask" "F.Paste")
			(net "P1V8_E")
		)
		(pad "F11" smd circle
			(at -5.500116 -10.500106)
			(size 0.4572 0.4572)
			(layers "F.Cu" "F.Mask" "F.Paste")
			(net "LSI_PROCMON")
		)
		(pad "F12" smd circle
			(at -4.500118 -10.500106)
			(size 0.4572 0.4572)
			(layers "F.Cu" "F.Mask" "F.Paste")
			(net "P1V8_E")
		)
		(pad "F13" smd circle
			(at -3.50012 -10.500106)
			(size 0.4572 0.4572)
			(layers "F.Cu" "F.Mask" "F.Paste")
			(net "XM_GP_CS_3#_TP")
		)
		(pad "F14" smd circle
			(at -2.500122 -10.500106)
			(size 0.4572 0.4572)
			(layers "F.Cu" "F.Mask" "F.Paste")
			(net "XM_DATA15")
		)
		(pad "F15" smd circle
			(at -1.500124 -10.500106)
			(size 0.4572 0.4572)
			(layers "F.Cu" "F.Mask" "F.Paste")
			(net "EXP_XM_ADDR_8")
		)
		(pad "F16" smd circle
			(at -0.500126 -10.500106)
			(size 0.4572 0.4572)
			(layers "F.Cu" "F.Mask" "F.Paste")
			(net "EXP_XM_ADDR_19")
		)
		(pad "F17" smd circle
			(at 0.500126 -10.500106)
			(size 0.4572 0.4572)
			(layers "F.Cu" "F.Mask" "F.Paste")
			(net "EXP_XM_ADDR_11")
		)
		(pad "F18" smd circle
			(at 1.500124 -10.500106)
			(size 0.4572 0.4572)
			(layers "F.Cu" "F.Mask" "F.Paste")
			(net "EXP_XM_ADDR_1")
		)
		(pad "F19" smd circle
			(at 2.500122 -10.500106)
			(size 0.4572 0.4572)
			(layers "F.Cu" "F.Mask" "F.Paste")
			(net "BMC_RMT_HEARTBEAT_LS")
		)
		(pad "F20" smd circle
			(at 3.50012 -10.500106)
			(size 0.4572 0.4572)
			(layers "F.Cu" "F.Mask" "F.Paste")
			(net "SCC_TYPE_0_LS")
		)
		(pad "F21" smd circle
			(at 4.500118 -10.500106)
			(size 0.4572 0.4572)
			(layers "F.Cu" "F.Mask" "F.Paste")
			(net "BMC_EXP_SPARE_0_R_LS")
		)
		(pad "F22" smd circle
			(at 5.500116 -10.500106)
			(size 0.4572 0.4572)
			(layers "F.Cu" "F.Mask" "F.Paste")
			(net "Net_1204")
		)
		(pad "F23" smd circle
			(at 6.500114 -10.500106)
			(size 0.4572 0.4572)
			(layers "F.Cu" "F.Mask" "F.Paste")
			(net "Net_1203")
		)
		(pad "F24" smd circle
			(at 7.500112 -10.500106)
			(size 0.4572 0.4572)
			(layers "F.Cu" "F.Mask" "F.Paste")
			(net "ICE_TRST_N")
		)
		(pad "F25" smd circle
			(at 8.50011 -10.500106)
			(size 0.4572 0.4572)
			(layers "F.Cu" "F.Mask" "F.Paste")
			(net "EXP_SIO_D_OUT")
		)
		(pad "F26" smd circle
			(at 9.500108 -10.500106)
			(size 0.4572 0.4572)
			(layers "F.Cu" "F.Mask" "F.Paste")
			(net "I2C_CLIP_SDA7_LS")
		)
		(pad "F27" smd circle
			(at 10.500106 -10.500106)
			(size 0.4572 0.4572)
			(layers "F.Cu" "F.Mask" "F.Paste")
			(net "GND")
		)
		(pad "F28" smd circle
			(at 11.500104 -10.500106)
			(size 0.4572 0.4572)
			(layers "F.Cu" "F.Mask" "F.Paste")
			(net "GND")
		)
		(pad "F29" smd circle
			(at 12.500102 -10.500106)
			(size 0.4572 0.4572)
			(layers "F.Cu" "F.Mask" "F.Paste")
			(net "I2C_BMC_LOC_SDA0_LS")
		)
		(pad "F30" smd circle
			(at 13.5001 -10.500106)
			(size 0.4572 0.4572)
			(layers "F.Cu" "F.Mask" "F.Paste")
			(net "GND")
		)
		(pad "F31" smd circle
			(at 14.500098 -10.500106)
			(size 0.4572 0.4572)
			(layers "F.Cu" "F.Mask" "F.Paste")
			(net "GND")
		)
		(pad "F32" smd circle
			(at 15.500096 -10.500106)
			(size 0.4572 0.4572)
			(layers "F.Cu" "F.Mask" "F.Paste")
			(net "GND")
		)
		(pad "G1" smd circle
			(at -15.500096 -9.500108)
			(size 0.4572 0.4572)
			(layers "F.Cu" "F.Mask" "F.Paste")
			(net "Net_1241")
		)
		(pad "G2" smd circle
			(at -14.500098 -9.500108)
			(size 0.4572 0.4572)
			(layers "F.Cu" "F.Mask" "F.Paste")
			(net "Net_1240")
		)
		(pad "G3" smd circle
			(at -13.5001 -9.500108)
			(size 0.4572 0.4572)
			(layers "F.Cu" "F.Mask" "F.Paste")
			(net "GND")
		)
		(pad "G4" smd circle
			(at -12.500102 -9.500108)
			(size 0.4572 0.4572)
			(layers "F.Cu" "F.Mask" "F.Paste")
			(net "Net_1239")
		)
		(pad "G5" smd circle
			(at -11.500104 -9.500108)
			(size 0.4572 0.4572)
			(layers "F.Cu" "F.Mask" "F.Paste")
			(net "GND")
		)
		(pad "G6" smd circle
			(at -10.500106 -9.500108)
			(size 0.4572 0.4572)
			(layers "F.Cu" "F.Mask" "F.Paste")
			(net "Net_1226")
		)
		(pad "G7" smd circle
			(at -9.500108 -9.500108)
			(size 0.4572 0.4572)
			(layers "F.Cu" "F.Mask" "F.Paste")
			(net "Net_1225")
		)
		(pad "G8" smd circle
			(at -8.50011 -9.500108)
			(size 0.4572 0.4572)
			(layers "F.Cu" "F.Mask" "F.Paste")
			(net "GND")
		)
		(pad "G9" smd circle
			(at -7.500112 -9.500108)
			(size 0.4572 0.4572)
			(layers "F.Cu" "F.Mask" "F.Paste")
			(net "ENCL_FAULT_LED_LS")
		)
		(pad "G10" smd circle
			(at -6.500114 -9.500108)
			(size 0.4572 0.4572)
			(layers "F.Cu" "F.Mask" "F.Paste")
			(net "EXP_BLINK_OUT")
		)
	)
)
